(kicad_pcb
	(version 20260206)
	(generator "pcbnew")
	(generator_version "10.0")
	(general
		(thickness 1.6)
		(legacy_teardrops no)
	)
	(paper "A4")
	(title_block
		(title "04192023_DAF0TMB3IC0_F0TG_MB_C_brd_V02_OCP.brd")
		(comment 1 "Grand Teton / footprints 7562-7567 of 8354")
	)
	(layers
		(0 "F.Cu" signal "TOP")
		(4 "In1.Cu" signal "GND")
		(6 "In2.Cu" signal "IN1")
		(8 "In3.Cu" signal "GND1")
		(10 "In4.Cu" signal "IN2")
		(12 "In5.Cu" signal "GND2")
		(14 "In6.Cu" signal "IN3")
		(16 "In7.Cu" signal "GND3")
		(18 "In8.Cu" signal "VCC")
		(20 "In9.Cu" signal "VCC1")
		(22 "In10.Cu" signal "GND4")
		(24 "In11.Cu" signal "IN4")
		(26 "In12.Cu" signal "GND5")
		(28 "In13.Cu" signal "IN5")
		(30 "In14.Cu" signal "GND6")
		(32 "In15.Cu" signal "IN6")
		(34 "In16.Cu" signal "GND7")
		(2 "B.Cu" signal "BOTTOM")
		(9 "F.Adhes" user "F.Adhesive")
		(11 "B.Adhes" user "B.Adhesive")
		(13 "F.Paste" user "Package Geometry/Pastemask Top")
		(15 "B.Paste" user "Package Geometry/Pastemask Bottom")
		(5 "F.SilkS" user "Ref Des/Silkscreen Top")
		(7 "B.SilkS" user "Ref Des/Silkscreen Bottom")
		(1 "F.Mask" user "Board Geometry/Soldermask Top")
		(3 "B.Mask" user "Board Geometry/Soldermask Bottom")
		(17 "Dwgs.User" user "User.Drawings")
		(19 "Cmts.User" user "User.Comments")
		(21 "Eco1.User" user "User.Eco1")
		(23 "Eco2.User" user "User.Eco2")
		(25 "Edge.Cuts" user "Board Geometry/Outline")
		(27 "Margin" user)
		(31 "F.CrtYd" user "Package Geometry/Place Bound Top")
		(29 "B.CrtYd" user "Package Geometry/Place Bound Bottom")
		(35 "F.Fab" user "Ref Des/Assembly Top")
		(33 "B.Fab" user "Ref Des/Assembly Bottom")
	)
	(footprint ""
		(layer "B.Cu")
		(at 363.341158 -271.395952 180)
		(property "Reference" "C2225"
			(at 0 0 0)
			(layer "B.SilkS")
			(hide yes)
			(effects
				(font
					(size 1.27 1.27)
				)
				(justify mirror)
			)
		)
		(property "Value" ""
			(at 0 0 0)
			(layer "B.Fab")
			(effects
				(font
					(size 1.27 1.27)
				)
				(justify mirror)
			)
		)
		(duplicate_pad_numbers_are_jumpers no)
		(fp_line
			(start 0.7874 0.4064)
			(end 0.7874 -0.4064)
			(stroke
				(width 0.1524)
				(type default)
			)
			(layer "B.SilkS")
		)
		(fp_line
			(start 0.7874 -0.4064)
			(end -0.7874 -0.4064)
			(stroke
				(width 0.1524)
				(type default)
			)
			(layer "B.SilkS")
		)
		(fp_line
			(start -0.7874 0.4064)
			(end 0.7874 0.4064)
			(stroke
				(width 0.1524)
				(type default)
			)
			(layer "B.SilkS")
		)
		(fp_line
			(start -0.7874 -0.4064)
			(end -0.7874 0.4064)
			(stroke
				(width 0.1524)
				(type default)
			)
			(layer "B.SilkS")
		)
		(fp_line
			(start 0.67945 0.3048)
			(end 0.67945 -0.305054)
			(stroke
				(width 0.1)
				(type default)
			)
			(layer "B.Fab")
		)
		(fp_line
			(start 0.67945 -0.305054)
			(end 0.12065 -0.305054)
			(stroke
				(width 0.1)
				(type default)
			)
			(layer "B.Fab")
		)
		(fp_line
			(start 0.12065 0.3048)
			(end 0.67945 0.3048)
			(stroke
				(width 0.1)
				(type default)
			)
			(layer "B.Fab")
		)
		(fp_line
			(start 0.12065 0.2794)
			(end 0.12065 0.3048)
			(stroke
				(width 0.1)
				(type default)
			)
			(layer "B.Fab")
		)
		(fp_line
			(start 0.12065 -0.2794)
			(end -0.12065 -0.2794)
			(stroke
				(width 0.1)
				(type default)
			)
			(layer "B.Fab")
		)
		(fp_line
			(start 0.12065 -0.305054)
			(end 0.12065 -0.2794)
			(stroke
				(width 0.1)
				(type default)
			)
			(layer "B.Fab")
		)
		(fp_line
			(start -0.120396 0.3048)
			(end -0.120396 0.2794)
			(stroke
				(width 0.1)
				(type default)
			)
			(layer "B.Fab")
		)
		(fp_line
			(start -0.120396 0.2794)
			(end 0.12065 0.2794)
			(stroke
				(width 0.1)
				(type default)
			)
			(layer "B.Fab")
		)
		(fp_line
			(start -0.12065 -0.2794)
			(end -0.12065 -0.3048)
			(stroke
				(width 0.1)
				(type default)
			)
			(layer "B.Fab")
		)
		(fp_line
			(start -0.12065 -0.3048)
			(end -0.67945 -0.3048)
			(stroke
				(width 0.1)
				(type default)
			)
			(layer "B.Fab")
		)
		(fp_line
			(start -0.67945 0.3048)
			(end -0.120396 0.3048)
			(stroke
				(width 0.1)
				(type default)
			)
			(layer "B.Fab")
		)
		(fp_line
			(start -0.67945 -0.3048)
			(end -0.67945 0.3048)
			(stroke
				(width 0.1)
				(type default)
			)
			(layer "B.Fab")
		)
		(pad "1" smd circle
			(at 0.40005 0)
			(size 0 0)
			(layers "B.Cu" "B.Mask" "B.Paste")
			(net "PVDDCR_CPU1_P0")
		)
		(pad "2" smd circle
			(at -0.40005 0)
			(size 0 0)
			(layers "B.Cu" "B.Mask" "B.Paste")
			(net "GND")
		)
	)
	(footprint ""
		(layer "B.Cu")
		(at 160.7312 -191.1604 -90)
		(property "Reference" "R541"
			(at 0 0 90)
			(layer "B.SilkS")
			(hide yes)
			(effects
				(font
					(size 1.27 1.27)
				)
				(justify mirror)
			)
		)
		(property "Value" ""
			(at 0 0 90)
			(layer "B.Fab")
			(effects
				(font
					(size 1.27 1.27)
				)
				(justify mirror)
			)
		)
		(duplicate_pad_numbers_are_jumpers no)
		(fp_line
			(start -0.7874 0.4064)
			(end 0.7874 0.4064)
			(stroke
				(width 0.1524)
				(type default)
			)
			(layer "B.SilkS")
		)
		(fp_line
			(start 0.7874 0.4064)
			(end 0.7874 -0.4064)
			(stroke
				(width 0.1524)
				(type default)
			)
			(layer "B.SilkS")
		)
		(fp_line
			(start -0.7874 -0.4064)
			(end -0.7874 0.4064)
			(stroke
				(width 0.1524)
				(type default)
			)
			(layer "B.SilkS")
		)
		(fp_line
			(start 0.7874 -0.4064)
			(end -0.7874 -0.4064)
			(stroke
				(width 0.1524)
				(type default)
			)
			(layer "B.SilkS")
		)
		(fp_line
			(start -0.67945 0.3048)
			(end -0.120396 0.3048)
			(stroke
				(width 0.1)
				(type default)
			)
			(layer "B.Fab")
		)
		(fp_line
			(start -0.120396 0.3048)
			(end -0.120396 0.2794)
			(stroke
				(width 0.1)
				(type default)
			)
			(layer "B.Fab")
		)
		(fp_line
			(start 0.12065 0.3048)
			(end 0.67945 0.3048)
			(stroke
				(width 0.1)
				(type default)
			)
			(layer "B.Fab")
		)
		(fp_line
			(start 0.67945 0.3048)
			(end 0.67945 -0.305054)
			(stroke
				(width 0.1)
				(type default)
			)
			(layer "B.Fab")
		)
		(fp_line
			(start -0.120396 0.2794)
			(end 0.12065 0.2794)
			(stroke
				(width 0.1)
				(type default)
			)
			(layer "B.Fab")
		)
		(fp_line
			(start 0.12065 0.2794)
			(end 0.12065 0.3048)
			(stroke
				(width 0.1)
				(type default)
			)
			(layer "B.Fab")
		)
		(fp_line
			(start -0.12065 -0.2794)
			(end -0.12065 -0.3048)
			(stroke
				(width 0.1)
				(type default)
			)
			(layer "B.Fab")
		)
		(fp_line
			(start 0.12065 -0.2794)
			(end -0.12065 -0.2794)
			(stroke
				(width 0.1)
				(type default)
			)
			(layer "B.Fab")
		)
		(fp_line
			(start -0.67945 -0.3048)
			(end -0.67945 0.3048)
			(stroke
				(width 0.1)
				(type default)
			)
			(layer "B.Fab")
		)
		(fp_line
			(start -0.12065 -0.3048)
			(end -0.67945 -0.3048)
			(stroke
				(width 0.1)
				(type default)
			)
			(layer "B.Fab")
		)
		(fp_line
			(start 0.12065 -0.305054)
			(end 0.12065 -0.2794)
			(stroke
				(width 0.1)
				(type default)
			)
			(layer "B.Fab")
		)
		(fp_line
			(start 0.67945 -0.305054)
			(end 0.12065 -0.305054)
			(stroke
				(width 0.1)
				(type default)
			)
			(layer "B.Fab")
		)
		(pad "1" smd circle
			(at 0.40005 0 90)
			(size 0 0)
			(layers "B.Cu" "B.Mask" "B.Paste")
			(net "PVDD11_S3_P1")
		)
		(pad "2" smd circle
			(at -0.40005 0 90)
			(size 0 0)
			(layers "B.Cu" "B.Mask" "B.Paste")
			(net "I3C_1_SPD_DDRGL_CPU1_R_SDA")
		)
	)
	(footprint ""
		(layer "B.Cu")
		(at 426.702474 -351.032826 90)
		(property "Reference" "PC211_1"
			(at 0 0 90)
			(layer "B.SilkS")
			(hide yes)
			(effects
				(font
					(size 1.27 1.27)
				)
				(justify mirror)
			)
		)
		(property "Value" ""
			(at 0 0 90)
			(layer "B.Fab")
			(effects
				(font
					(size 1.27 1.27)
				)
				(justify mirror)
			)
		)
		(duplicate_pad_numbers_are_jumpers no)
		(fp_line
			(start 1.524 -0.762)
			(end -1.524 -0.762)
			(stroke
				(width 0.1524)
				(type default)
			)
			(layer "B.SilkS")
		)
		(fp_line
			(start -1.524 -0.762)
			(end -1.524 0.762)
			(stroke
				(width 0.1524)
				(type default)
			)
			(layer "B.SilkS")
		)
		(fp_line
			(start 1.524 0.762)
			(end 1.524 -0.762)
			(stroke
				(width 0.1524)
				(type default)
			)
			(layer "B.SilkS")
		)
		(fp_line
			(start -1.524 0.762)
			(end 1.524 0.762)
			(stroke
				(width 0.1524)
				(type default)
			)
			(layer "B.SilkS")
		)
		(fp_line
			(start 1.1049 -0.724916)
			(end 1.1049 0.724916)
			(stroke
				(width 0.1)
				(type default)
			)
			(layer "B.Fab")
		)
		(fp_line
			(start -1.1049 -0.724916)
			(end 1.1049 -0.724916)
			(stroke
				(width 0.1)
				(type default)
			)
			(layer "B.Fab")
		)
		(fp_line
			(start 1.1049 0.724916)
			(end -1.1049 0.724916)
			(stroke
				(width 0.1)
				(type default)
			)
			(layer "B.Fab")
		)
		(fp_line
			(start -1.1049 0.724916)
			(end -1.1049 -0.724916)
			(stroke
				(width 0.1)
				(type default)
			)
			(layer "B.Fab")
		)
		(pad "1" smd rect
			(at 0.889 0 90)
			(size 1.016 1.27)
			(layers "B.Cu" "B.Mask" "B.Paste")
			(net "SW_P12V_AUX_PVDD11_S3_P0_FLT")
		)
		(pad "2" smd rect
			(at -0.889 0 90)
			(size 1.016 1.27)
			(layers "B.Cu" "B.Mask" "B.Paste")
			(net "GND")
		)
	)
	(footprint ""
		(layer "B.Cu")
		(at 404.475696 -340.622382)
		(property "Reference" "U82"
			(at 5.969 -0.980948 0)
			(unlocked yes)
			(layer "B.SilkS")
			(effects
				(font
					(size 0.7874 0.5842)
					(thickness 0.1524)
				)
				(justify left mirror)
			)
		)
		(property "Value" ""
			(at 0 0 0)
			(layer "B.Fab")
			(effects
				(font
					(size 1.27 1.27)
				)
				(justify mirror)
			)
		)
		(duplicate_pad_numbers_are_jumpers no)
		(fp_line
			(start -2.0574 -1.651)
			(end -2.0574 1.651)
			(stroke
				(width 0.1524)
				(type default)
			)
			(layer "B.SilkS")
		)
		(fp_line
			(start -2.0574 1.651)
			(end 2.0574 1.651)
			(stroke
				(width 0.1524)
				(type default)
			)
			(layer "B.SilkS")
		)
		(fp_line
			(start -0.381 -1.651)
			(end -2.0574 -1.651)
			(stroke
				(width 0.1524)
				(type default)
			)
			(layer "B.SilkS")
		)
		(fp_line
			(start 0 -1.016)
			(end -0.381 -1.651)
			(stroke
				(width 0.1524)
				(type default)
			)
			(layer "B.SilkS")
		)
		(fp_line
			(start 0.381 -1.651)
			(end 0 -1.016)
			(stroke
				(width 0.1524)
				(type default)
			)
			(layer "B.SilkS")
		)
		(fp_line
			(start 2.0574 -1.651)
			(end 0.381 -1.651)
			(stroke
				(width 0.1524)
				(type default)
			)
			(layer "B.SilkS")
		)
		(fp_line
			(start 2.0574 1.651)
			(end 2.0574 -1.651)
			(stroke
				(width 0.1524)
				(type default)
			)
			(layer "B.SilkS")
		)
		(fp_poly
			(pts
				(xy 2.159 -1.016) (xy 2.71272 -0.719328) (xy 2.71272 -1.344168)
			)
			(stroke
				(width 0)
				(type default)
			)
			(fill yes)
			(layer "B.SilkS")
		)
		(fp_line
			(start -1.599946 -1.199896)
			(end -1.599946 1.199896)
			(stroke
				(width 0.1)
				(type default)
			)
			(layer "B.Fab")
		)
		(fp_line
			(start -1.599946 1.199896)
			(end -0.899922 1.199896)
			(stroke
				(width 0.1)
				(type default)
			)
			(layer "B.Fab")
		)
		(fp_line
			(start -0.899922 -1.549908)
			(end -0.899922 -1.199896)
			(stroke
				(width 0.1)
				(type default)
			)
			(layer "B.Fab")
		)
		(fp_line
			(start -0.899922 -1.199896)
			(end -1.599946 -1.199896)
			(stroke
				(width 0.1)
				(type default)
			)
			(layer "B.Fab")
		)
		(fp_line
			(start -0.899922 1.199896)
			(end -0.899922 1.549908)
			(stroke
				(width 0.1)
				(type default)
			)
			(layer "B.Fab")
		)
		(fp_line
			(start -0.899922 1.549908)
			(end 0.899922 1.549908)
			(stroke
				(width 0.1)
				(type default)
			)
			(layer "B.Fab")
		)
		(fp_line
			(start 0.899922 -1.549908)
			(end -0.899922 -1.549908)
			(stroke
				(width 0.1)
				(type default)
			)
			(layer "B.Fab")
		)
		(fp_line
			(start 0.899922 -1.199896)
			(end 0.899922 -1.549908)
			(stroke
				(width 0.1)
				(type default)
			)
			(layer "B.Fab")
		)
		(fp_line
			(start 0.899922 1.199896)
			(end 1.599946 1.199896)
			(stroke
				(width 0.1)
				(type default)
			)
			(layer "B.Fab")
		)
		(fp_line
			(start 0.899922 1.549908)
			(end 0.899922 1.199896)
			(stroke
				(width 0.1)
				(type default)
			)
			(layer "B.Fab")
		)
		(fp_line
			(start 1.599946 -1.199896)
			(end 0.899922 -1.199896)
			(stroke
				(width 0.1)
				(type default)
			)
			(layer "B.Fab")
		)
		(fp_line
			(start 1.599946 1.199896)
			(end 1.599946 -1.199896)
			(stroke
				(width 0.1)
				(type default)
			)
			(layer "B.Fab")
		)
		(fp_poly
			(pts
				(xy 2.71272 -0.719328) (xy 2.71272 -1.344168) (xy 2.159 -1.016)
			)
			(stroke
				(width 0)
				(type default)
			)
			(fill yes)
			(layer "B.Fab")
		)
		(pad "1" smd rect
			(at 1.225042 -0.94996 270)
			(size 0.5588 1.3462)
			(layers "B.Cu" "B.Mask" "B.Paste")
			(net "Net_10732")
		)
		(pad "2" smd rect
			(at 1.225042 0 270)
			(size 0.5588 1.3462)
			(layers "B.Cu" "B.Mask" "B.Paste")
			(net "BOOT_RDY_R1_N")
		)
		(pad "3" smd rect
			(at 1.225042 0.94996 270)
			(size 0.5588 1.3462)
			(layers "B.Cu" "B.Mask" "B.Paste")
			(net "GND")
		)
		(pad "4" smd rect
			(at -1.225042 0.94996 270)
			(size 0.5588 1.3462)
			(layers "B.Cu" "B.Mask" "B.Paste")
			(net "BOOT_RDY_BUF_R_LED")
		)
		(pad "5" smd rect
			(at -1.225042 -0.94996 270)
			(size 0.5588 1.3462)
			(layers "B.Cu" "B.Mask" "B.Paste")
			(net "P1V8_AUX")
		)
	)
	(footprint ""
		(layer "B.Cu")
		(at 231.074722 -323.913754)
		(property "Reference" "R1251"
			(at 0 0 0)
			(layer "B.SilkS")
			(hide yes)
			(effects
				(font
					(size 1.27 1.27)
				)
				(justify mirror)
			)
		)
		(property "Value" ""
			(at 0 0 0)
			(layer "B.Fab")
			(effects
				(font
					(size 1.27 1.27)
				)
				(justify mirror)
			)
		)
		(duplicate_pad_numbers_are_jumpers no)
		(fp_line
			(start -0.7874 -0.4064)
			(end -0.7874 0.4064)
			(stroke
				(width 0.1524)
				(type default)
			)
			(layer "B.SilkS")
		)
		(fp_line
			(start -0.7874 0.4064)
			(end 0.7874 0.4064)
			(stroke
				(width 0.1524)
				(type default)
			)
			(layer "B.SilkS")
		)
		(fp_line
			(start 0.7874 -0.4064)
			(end -0.7874 -0.4064)
			(stroke
				(width 0.1524)
				(type default)
			)
			(layer "B.SilkS")
		)
		(fp_line
			(start 0.7874 0.4064)
			(end 0.7874 -0.4064)
			(stroke
				(width 0.1524)
				(type default)
			)
			(layer "B.SilkS")
		)
		(fp_line
			(start -0.67945 -0.3048)
			(end -0.67945 0.3048)
			(stroke
				(width 0.1)
				(type default)
			)
			(layer "B.Fab")
		)
		(fp_line
			(start -0.67945 0.3048)
			(end -0.120396 0.3048)
			(stroke
				(width 0.1)
				(type default)
			)
			(layer "B.Fab")
		)
		(fp_line
			(start -0.12065 -0.3048)
			(end -0.67945 -0.3048)
			(stroke
				(width 0.1)
				(type default)
			)
			(layer "B.Fab")
		)
		(fp_line
			(start -0.12065 -0.2794)
			(end -0.12065 -0.3048)
			(stroke
				(width 0.1)
				(type default)
			)
			(layer "B.Fab")
		)
		(fp_line
			(start -0.120396 0.2794)
			(end 0.12065 0.2794)
			(stroke
				(width 0.1)
				(type default)
			)
			(layer "B.Fab")
		)
		(fp_line
			(start -0.120396 0.3048)
			(end -0.120396 0.2794)
			(stroke
				(width 0.1)
				(type default)
			)
			(layer "B.Fab")
		)
		(fp_line
			(start 0.12065 -0.305054)
			(end 0.12065 -0.2794)
			(stroke
				(width 0.1)
				(type default)
			)
			(layer "B.Fab")
		)
		(fp_line
			(start 0.12065 -0.2794)
			(end -0.12065 -0.2794)
			(stroke
				(width 0.1)
				(type default)
			)
			(layer "B.Fab")
		)
		(fp_line
			(start 0.12065 0.2794)
			(end 0.12065 0.3048)
			(stroke
				(width 0.1)
				(type default)
			)
			(layer "B.Fab")
		)
		(fp_line
			(start 0.12065 0.3048)
			(end 0.67945 0.3048)
			(stroke
				(width 0.1)
				(type default)
			)
			(layer "B.Fab")
		)
		(fp_line
			(start 0.67945 -0.305054)
			(end 0.12065 -0.305054)
			(stroke
				(width 0.1)
				(type default)
			)
			(layer "B.Fab")
		)
		(fp_line
			(start 0.67945 0.3048)
			(end 0.67945 -0.305054)
			(stroke
				(width 0.1)
				(type default)
			)
			(layer "B.Fab")
		)
		(pad "1" smd rect
			(at 0.40005 0)
			(size 0.4572 0.508)
			(layers "B.Cu" "B.Mask" "B.Paste")
			(net "P1V2_AUX_ADC")
		)
		(pad "2" smd rect
			(at -0.40005 0)
			(size 0.4572 0.508)
			(layers "B.Cu" "B.Mask" "B.Paste")
			(net "P1V2_AUX_ADC_TIC")
		)
	)
	(footprint ""
		(layer "B.Cu")
		(at 341.906098 -395.148562 90)
		(property "Reference" "C610"
			(at 0 0 90)
			(layer "B.SilkS")
			(hide yes)
			(effects
				(font
					(size 1.27 1.27)
				)
				(justify mirror)
			)
		)
		(property "Value" ""
			(at 0 0 90)
			(layer "B.Fab")
			(effects
				(font
					(size 1.27 1.27)
				)
				(justify mirror)
			)
		)
		(duplicate_pad_numbers_are_jumpers no)
		(fp_line
			(start 0.299974 -0.150114)
			(end -0.299974 -0.150114)
			(stroke
				(width 0.1)
				(type default)
			)
			(layer "B.Fab")
		)
		(fp_line
			(start -0.299974 -0.150114)
			(end -0.299974 0.150114)
			(stroke
				(width 0.1)
				(type default)
			)
			(layer "B.Fab")
		)
		(fp_line
			(start 0.299974 0.150114)
			(end 0.299974 -0.150114)
			(stroke
				(width 0.1)
				(type default)
			)
			(layer "B.Fab")
		)
		(fp_line
			(start -0.299974 0.150114)
			(end 0.299974 0.150114)
			(stroke
				(width 0.1)
				(type default)
			)
			(layer "B.Fab")
		)
		(pad "1" smd rect
			(at 0.2667 0 270)
			(size 0.3048 0.381)
			(layers "B.Cu" "B.Mask" "B.Paste")
			(net "P0V9_CPU0_RT_2D")
		)
		(pad "2" smd rect
			(at -0.2667 0 270)
			(size 0.3048 0.381)
			(layers "B.Cu" "B.Mask" "B.Paste")
			(net "GND")
		)
	)
)
